# TIMECARD (Time Appliance Project (Time Card)) — schematic netlist excerpt (pin names and nets, part order shuffled) for the footprints in the layout excerpt that follows; sources: Cadence DE-HDL packaged netlist, KiCad conversion of R4006-B0001-02_R01.brd

R371  RESISTOR  49.9OHM 1%  pkg SMC_0402R_H016  page 23 : \1\ = BF_ANT1_IN ; \2\ = ANT1_IN
DS1  OPTICAL  pkg SMC_DS_063X031_V4  page 26 : A = UNNAMED_14_OPTICAL_I12_A ; C = LED_DATOUT3

(kicad_pcb
	(version 20260206)
	(generator "pcbnew")
	(generator_version "10.0")
	(general
		(thickness 1.6)
		(legacy_teardrops no)
	)
	(paper "A4")
	(title_block
		(title "timecard-production-celestica-r4006 — R4006-B0001-02_R01.brd")
		(comment 1 "Time Appliance Project (Time Card) / footprints 68-69 of 1113")
	)
	(layers
		(0 "F.Cu" signal "TOP")
		(4 "In1.Cu" signal "L02_GND1")
		(6 "In2.Cu" signal "L03_SIG1")
		(8 "In3.Cu" signal "L04_GND2")
		(10 "In4.Cu" signal "L05_VCC1")
		(12 "In5.Cu" signal "L06_VCC2")
		(14 "In6.Cu" signal "L07_GND3")
		(16 "In7.Cu" signal "L08_SIG2")
		(18 "In8.Cu" signal "L09_GND4")
		(2 "B.Cu" signal "BOTTOM")
		(9 "F.Adhes" user "F.Adhesive")
		(11 "B.Adhes" user "B.Adhesive")
		(13 "F.Paste" user "Package Geometry/Pastemask Top")
		(15 "B.Paste" user "Package Geometry/Pastemask Bottom")
		(5 "F.SilkS" user "Ref Des/Silkscreen Top")
		(7 "B.SilkS" user "Ref Des/Silkscreen Bottom")
		(1 "F.Mask" user "Board Geometry/Soldermask Top")
		(3 "B.Mask" user "Board Geometry/Soldermask Bottom")
		(17 "Dwgs.User" user "User.Drawings")
		(19 "Cmts.User" user "User.Comments")
		(21 "Eco1.User" user "User.Eco1")
		(23 "Eco2.User" user "User.Eco2")
		(25 "Edge.Cuts" user "Board Geometry/Outline")
		(27 "Margin" user)
		(31 "F.CrtYd" user "Package Geometry/Place Bound Top")
		(29 "B.CrtYd" user "Package Geometry/Place Bound Bottom")
		(35 "F.Fab" user "Ref Des/Assembly Top")
		(33 "B.Fab" user "Ref Des/Assembly Bottom")
	)
	(footprint ""
		(layer "F.Cu")
		(at 138.050016 -107.849924 -90)
		(property "Reference" "DS1"
			(at -0.100076 1.866646 90)
			(unlocked yes)
			(layer "F.SilkS")
			(effects
				(font
					(size 0.7874 0.5842)
					(thickness 0.1524)
				)
			)
		)
		(property "Value" ""
			(at 0 0 270)
			(layer "F.Fab")
			(effects
				(font
					(size 1.27 1.27)
				)
			)
		)
		(property "User Part Number" "PARTNUM*"
			(at 0.1778 2.422881 270)
			(unlocked yes)
			(layer "Cmts.User")
			(hide yes)
			(effects
				(font
					(size 0.786892 0.583946)
					(thickness 0.000001)
				)
			)
		)
		(property "Device Type" "OPTICAL-G170-10143-01"
			(at 0.1778 1.483081 270)
			(unlocked yes)
			(layer "F.Fab")
			(hide yes)
			(effects
				(font
					(size 0.786892 0.583946)
					(thickness 0.000001)
				)
			)
		)
		(duplicate_pad_numbers_are_jumpers no)
		(fp_line
			(start -1.3208 1.2192)
			(end -2.5908 1.2192)
			(stroke
				(width 0.1)
				(type default)
			)
			(layer "F.SilkS")
		)
		(fp_line
			(start -1.397508 0.704088)
			(end -1.397508 -0.704088)
			(stroke
				(width 0.1)
				(type default)
			)
			(layer "F.SilkS")
		)
		(fp_line
			(start 1.397508 0.704088)
			(end -1.397508 0.704088)
			(stroke
				(width 0.1)
				(type default)
			)
			(layer "F.SilkS")
		)
		(fp_line
			(start -1.9558 0.5842)
			(end -1.9558 1.8542)
			(stroke
				(width 0.1)
				(type default)
			)
			(layer "F.SilkS")
		)
		(fp_line
			(start -1.397508 -0.704088)
			(end 1.397508 -0.704088)
			(stroke
				(width 0.1)
				(type default)
			)
			(layer "F.SilkS")
		)
		(fp_line
			(start 1.397508 -0.704088)
			(end 1.397508 0.704088)
			(stroke
				(width 0.1)
				(type default)
			)
			(layer "F.SilkS")
		)
		(fp_rect
			(start 1.905508 0.704088)
			(end 1.397508 -0.704088)
			(stroke
				(width 0)
				(type default)
			)
			(fill yes)
			(layer "F.SilkS")
		)
		(fp_rect
			(start 1.905508 0.958088)
			(end -1.651508 -0.958088)
			(stroke
				(width 0)
				(type default)
			)
			(fill no)
			(layer "F.CrtYd")
		)
		(fp_line
			(start -1.3208 1.0922)
			(end -2.5908 1.0922)
			(stroke
				(width 0.1)
				(type default)
			)
			(layer "F.Fab")
		)
		(fp_line
			(start -1.9558 0.4572)
			(end -1.9558 1.7272)
			(stroke
				(width 0.1)
				(type default)
			)
			(layer "F.Fab")
		)
		(fp_line
			(start -0.850138 0.450088)
			(end 0.850138 0.450088)
			(stroke
				(width 0.1)
				(type default)
			)
			(layer "F.Fab")
		)
		(fp_line
			(start 0.850138 0.450088)
			(end 0.850138 -0.450088)
			(stroke
				(width 0.1)
				(type default)
			)
			(layer "F.Fab")
		)
		(fp_line
			(start -0.850138 -0.450088)
			(end -0.850138 0.450088)
			(stroke
				(width 0.1)
				(type default)
			)
			(layer "F.Fab")
		)
		(fp_line
			(start 0.850138 -0.450088)
			(end -0.850138 -0.450088)
			(stroke
				(width 0.1)
				(type default)
			)
			(layer "F.Fab")
		)
		(fp_rect
			(start 0.850138 0.450088)
			(end 0.342138 -0.450088)
			(stroke
				(width 0)
				(type default)
			)
			(fill yes)
			(layer "F.Fab")
		)
		(fp_text user "C"
			(at 1.582674 1.398016 0)
			(unlocked yes)
			(layer "F.SilkS")
			(effects
				(font
					(size 0.635 0.4064)
					(thickness 0.1524)
				)
			)
		)
		(fp_text user "A"
			(at -2.024126 0.382016 0)
			(unlocked yes)
			(layer "F.SilkS")
			(effects
				(font
					(size 0.635 0.4064)
					(thickness 0.1524)
				)
			)
		)
		(fp_text user "A"
			(at -1.700276 0.255016 0)
			(unlocked yes)
			(layer "F.Fab")
			(effects
				(font
					(size 0.7874 0.5842)
					(thickness 0.1524)
				)
			)
		)
		(fp_text user "C"
			(at 1.082294 -0.887984 0)
			(unlocked yes)
			(layer "F.Fab")
			(effects
				(font
					(size 0.7874 0.5842)
					(thickness 0.1524)
				)
			)
		)
		(pad "A" smd rect
			(at -0.749808 0 270)
			(size 0.7874 0.7874)
			(layers "F.Cu" "F.Mask" "F.Paste")
			(net "UNNAMED_14_OPTICAL_I12_A")
		)
		(pad "C" smd rect
			(at 0.749808 0 270)
			(size 0.7874 0.7874)
			(layers "F.Cu" "F.Mask" "F.Paste")
			(net "LED_DATOUT3")
		)
	)
	(footprint ""
		(layer "F.Cu")
		(at 12.1412 -65.786 90)
		(property "Reference" "R371"
			(at 5.334 -0.29083 90)
			(unlocked yes)
			(layer "F.SilkS")
			(effects
				(font
					(size 0.7874 0.5842)
					(thickness 0.1524)
				)
			)
		)
		(property "Value" "VAL*"
			(at 0.02032 2.13233 90)
			(unlocked yes)
			(layer "F.Fab")
			(hide yes)
			(effects
				(font
					(size 0.7874 0.5842)
					(thickness 0.1524)
				)
			)
		)
		(property "Tolerance" "TOL*"
			(at 0.044704 3.05435 90)
			(unlocked yes)
			(layer "Cmts.User")
			(hide yes)
			(effects
				(font
					(size 0.7874 0.5842)
					(thickness 0.1524)
				)
			)
		)
		(property "User Part Number" "PARTNUM*"
			(at 0.02032 4.024884 90)
			(unlocked yes)
			(layer "Cmts.User")
			(hide yes)
			(effects
				(font
					(size 0.7874 0.5842)
					(thickness 0.1524)
				)
			)
		)
		(property "Device Type" "RESISTOR-G155-149R9-01,49.9OHMA"
			(at 0.008382 1.210564 90)
			(unlocked yes)
			(layer "F.Fab")
			(hide yes)
			(effects
				(font
					(size 0.7874 0.5842)
					(thickness 0.1524)
				)
			)
		)
		(duplicate_pad_numbers_are_jumpers no)
		(fp_line
			(start 1.143 -0.5588)
			(end -1.143 -0.5588)
			(stroke
				(width 0.1)
				(type default)
			)
			(layer "F.SilkS")
		)
		(fp_line
			(start -1.143 -0.5588)
			(end -1.143 0.5588)
			(stroke
				(width 0.1)
				(type default)
			)
			(layer "F.SilkS")
		)
		(fp_line
			(start 1.143 0.5588)
			(end 1.143 -0.5588)
			(stroke
				(width 0.1)
				(type default)
			)
			(layer "F.SilkS")
		)
		(fp_line
			(start -1.143 0.5588)
			(end 1.143 0.5588)
			(stroke
				(width 0.1)
				(type default)
			)
			(layer "F.SilkS")
		)
		(fp_poly
			(pts
				(xy -1.143 0.5588) (xy 1.143 0.5588) (xy 1.143 -0.5588) (xy -1.143 -0.5588)
			)
			(stroke
				(width 0)
				(type default)
			)
			(fill no)
			(layer "F.CrtYd")
		)
		(fp_line
			(start 0.508 -0.3048)
			(end -0.508 -0.3048)
			(stroke
				(width 0.1)
				(type default)
			)
			(layer "F.Fab")
		)
		(fp_line
			(start -0.508 -0.3048)
			(end -0.508 0.3048)
			(stroke
				(width 0.1)
				(type default)
			)
			(layer "F.Fab")
		)
		(fp_line
			(start 0.508 0.3048)
			(end 0.508 -0.3048)
			(stroke
				(width 0.1)
				(type default)
			)
			(layer "F.Fab")
		)
		(fp_line
			(start -0.508 0.3048)
			(end 0.508 0.3048)
			(stroke
				(width 0.1)
				(type default)
			)
			(layer "F.Fab")
		)
		(pad "1" smd rect
			(at -0.5334 0 90)
			(size 0.7112 0.6096)
			(layers "F.Cu" "F.Mask" "F.Paste")
			(net "BF_ANT1_IN")
		)
		(pad "2" smd rect
			(at 0.5334 0 90)
			(size 0.7112 0.6096)
			(layers "F.Cu" "F.Mask" "F.Paste")
			(net "ANT1_IN")
		)
		(zone
			(layer "F.Cu")
			(hatch none 0.5)
			(connect_pads
				(clearance 0)
			)
			(min_thickness 0.25)
			(keepout
				(tracks allowed)
				(vias not_allowed)
				(pads allowed)
				(copperpour not_allowed)
				(footprints allowed)
			)
			(placement
				(enabled no)
				(sheetname "")
			)
			(fill
				(thermal_gap 0.5)
				(thermal_bridge_width 0.5)
				(island_removal_mode 0)
			)
			(polygon
				(pts
					(xy 12.446 -65.7098) (xy 12.446 -65.8622) (xy 11.8364 -65.8622) (xy 11.8364 -65.7098)
				)
			)
		)
		(zone
			(layer "F.Cu")
			(hatch none 0.5)
			(connect_pads
				(clearance 0)
			)
			(min_thickness 0.25)
			(keepout
				(tracks not_allowed)
				(vias allowed)
				(pads allowed)
				(copperpour not_allowed)
				(footprints allowed)
			)
			(placement
				(enabled no)
				(sheetname "")
			)
			(fill
				(thermal_gap 0.5)
				(thermal_bridge_width 0.5)
				(island_removal_mode 0)
			)
			(polygon
				(pts
					(xy 12.446 -65.7098) (xy 12.446 -65.8622) (xy 11.8364 -65.8622) (xy 11.8364 -65.7098)
				)
			)
		)
	)
)
